# TIMECARD (Time Appliance Project (Time Card)) — schematic netlist excerpt (pin names and nets, part order shuffled) for the footprints in the layout excerpt that follows; sources: Cadence DE-HDL packaged netlist, KiCad conversion of R4006-B0001-02_R01.brd

R464  RESISTOR  0OHM -  pkg SMC_0402R_H016  page 24 : \1\ = FPGA_FLASH_DQ2 ; \2\ = FLASH_DQ2
L6  FERRITEBEAD  26OHM 25%  pkg SMC_0603R_H030  page 30 : \1\ = XP3R3V ; \2\ = XP1R8V_VIN

(kicad_pcb
	(version 20260206)
	(generator "pcbnew")
	(generator_version "10.0")
	(general
		(thickness 1.6)
		(legacy_teardrops no)
	)
	(paper "A4")
	(title_block
		(title "timecard-production-celestica-r4006 — R4006-B0001-02_R01.brd")
		(comment 1 "Time Appliance Project (Time Card) / footprints 379-380 of 1113")
	)
	(layers
		(0 "F.Cu" signal "TOP")
		(4 "In1.Cu" signal "L02_GND1")
		(6 "In2.Cu" signal "L03_SIG1")
		(8 "In3.Cu" signal "L04_GND2")
		(10 "In4.Cu" signal "L05_VCC1")
		(12 "In5.Cu" signal "L06_VCC2")
		(14 "In6.Cu" signal "L07_GND3")
		(16 "In7.Cu" signal "L08_SIG2")
		(18 "In8.Cu" signal "L09_GND4")
		(2 "B.Cu" signal "BOTTOM")
		(9 "F.Adhes" user "F.Adhesive")
		(11 "B.Adhes" user "B.Adhesive")
		(13 "F.Paste" user "Package Geometry/Pastemask Top")
		(15 "B.Paste" user "Package Geometry/Pastemask Bottom")
		(5 "F.SilkS" user "Ref Des/Silkscreen Top")
		(7 "B.SilkS" user "Ref Des/Silkscreen Bottom")
		(1 "F.Mask" user "Board Geometry/Soldermask Top")
		(3 "B.Mask" user "Board Geometry/Soldermask Bottom")
		(17 "Dwgs.User" user "User.Drawings")
		(19 "Cmts.User" user "User.Comments")
		(21 "Eco1.User" user "User.Eco1")
		(23 "Eco2.User" user "User.Eco2")
		(25 "Edge.Cuts" user "Board Geometry/Outline")
		(27 "Margin" user)
		(31 "F.CrtYd" user "Package Geometry/Place Bound Top")
		(29 "B.CrtYd" user "Package Geometry/Place Bound Bottom")
		(35 "F.Fab" user "Ref Des/Assembly Top")
		(33 "B.Fab" user "Ref Des/Assembly Bottom")
	)
	(footprint ""
		(layer "F.Cu")
		(at 125.2982 -63.3222 90)
		(property "Reference" "L6"
			(at -0.762 -1.43383 90)
			(unlocked yes)
			(layer "F.SilkS")
			(effects
				(font
					(size 0.7874 0.5842)
					(thickness 0.1524)
				)
				(justify left)
			)
		)
		(property "Value" "VAL*"
			(at -0.9398 3.70967 90)
			(unlocked yes)
			(layer "F.Fab")
			(hide yes)
			(effects
				(font
					(size 0.7874 0.5842)
					(thickness 0.1524)
				)
				(justify left)
			)
		)
		(property "Device Type" "FERRITEBEAD-G191-10101-01,26OHA"
			(at -0.9906 1.22047 90)
			(unlocked yes)
			(layer "F.Fab")
			(hide yes)
			(effects
				(font
					(size 0.7874 0.5842)
					(thickness 0.1524)
				)
				(justify left)
			)
		)
		(property "User Part Number" "PARTNUM*"
			(at -2.54 2.46507 90)
			(unlocked yes)
			(layer "Cmts.User")
			(hide yes)
			(effects
				(font
					(size 0.7874 0.5842)
					(thickness 0.1524)
				)
				(justify left)
			)
		)
		(property "Tolerance" "TOL*"
			(at -0.9906 5.00507 90)
			(unlocked yes)
			(layer "Cmts.User")
			(hide yes)
			(effects
				(font
					(size 0.7874 0.5842)
					(thickness 0.1524)
				)
				(justify left)
			)
		)
		(duplicate_pad_numbers_are_jumpers no)
		(fp_line
			(start 1.3208 -0.7112)
			(end 1.3208 0.7112)
			(stroke
				(width 0.1)
				(type default)
			)
			(layer "F.SilkS")
		)
		(fp_line
			(start -1.3208 -0.7112)
			(end 1.3208 -0.7112)
			(stroke
				(width 0.1)
				(type default)
			)
			(layer "F.SilkS")
		)
		(fp_line
			(start 1.3208 0.7112)
			(end -1.3208 0.7112)
			(stroke
				(width 0.1)
				(type default)
			)
			(layer "F.SilkS")
		)
		(fp_line
			(start -1.3208 0.7112)
			(end -1.3208 -0.7112)
			(stroke
				(width 0.1)
				(type default)
			)
			(layer "F.SilkS")
		)
		(fp_rect
			(start 1.3208 0.7112)
			(end -1.3208 -0.7112)
			(stroke
				(width 0)
				(type default)
			)
			(fill no)
			(layer "F.CrtYd")
		)
		(fp_line
			(start 0.8128 -0.4572)
			(end 0.8128 0.4572)
			(stroke
				(width 0.1)
				(type default)
			)
			(layer "F.Fab")
		)
		(fp_line
			(start -0.8128 -0.4572)
			(end 0.8128 -0.4572)
			(stroke
				(width 0.1)
				(type default)
			)
			(layer "F.Fab")
		)
		(fp_line
			(start 0.8128 0.4572)
			(end -0.8128 0.4572)
			(stroke
				(width 0.1)
				(type default)
			)
			(layer "F.Fab")
		)
		(fp_line
			(start -0.8128 0.4572)
			(end -0.8128 -0.4572)
			(stroke
				(width 0.1)
				(type default)
			)
			(layer "F.Fab")
		)
		(pad "1" smd rect
			(at -0.6858 0 90)
			(size 0.762 0.8636)
			(layers "F.Cu" "F.Mask" "F.Paste")
			(net "XP3R3V")
		)
		(pad "2" smd rect
			(at 0.6858 0 90)
			(size 0.762 0.8636)
			(layers "F.Cu" "F.Mask" "F.Paste")
			(net "XP1R8V_VIN")
		)
		(zone
			(layer "F.Cu")
			(hatch none 0.5)
			(connect_pads
				(clearance 0)
			)
			(min_thickness 0.25)
			(keepout
				(tracks allowed)
				(vias not_allowed)
				(pads allowed)
				(copperpour not_allowed)
				(footprints allowed)
			)
			(placement
				(enabled no)
				(sheetname "")
			)
			(fill
				(thermal_gap 0.5)
				(thermal_bridge_width 0.5)
				(island_removal_mode 0)
			)
			(polygon
				(pts
					(xy 125.7554 -63.4746) (xy 124.841 -63.4746) (xy 124.841 -63.1698) (xy 125.7554 -63.1698)
				)
			)
		)
	)
	(footprint ""
		(layer "F.Cu")
		(at 98.298 -87.503 90)
		(property "Reference" "R464"
			(at 2.794 -0.59563 90)
			(unlocked yes)
			(layer "F.SilkS")
			(effects
				(font
					(size 0.7874 0.5842)
					(thickness 0.1524)
				)
			)
		)
		(property "Value" "VAL*"
			(at 0.02032 2.13233 90)
			(unlocked yes)
			(layer "F.Fab")
			(hide yes)
			(effects
				(font
					(size 0.7874 0.5842)
					(thickness 0.1524)
				)
			)
		)
		(property "Tolerance" "TOL*"
			(at 0.044704 3.05435 90)
			(unlocked yes)
			(layer "Cmts.User")
			(hide yes)
			(effects
				(font
					(size 0.7874 0.5842)
					(thickness 0.1524)
				)
			)
		)
		(property "User Part Number" "PARTNUM*"
			(at 0.02032 4.024884 90)
			(unlocked yes)
			(layer "Cmts.User")
			(hide yes)
			(effects
				(font
					(size 0.7874 0.5842)
					(thickness 0.1524)
				)
			)
		)
		(property "Device Type" "RESISTOR-G155-100R0-J0,0OHM,-"
			(at 0.008382 1.210564 90)
			(unlocked yes)
			(layer "F.Fab")
			(hide yes)
			(effects
				(font
					(size 0.7874 0.5842)
					(thickness 0.1524)
				)
			)
		)
		(duplicate_pad_numbers_are_jumpers no)
		(fp_line
			(start 1.143 -0.5588)
			(end -1.143 -0.5588)
			(stroke
				(width 0.1)
				(type default)
			)
			(layer "F.SilkS")
		)
		(fp_line
			(start -1.143 -0.5588)
			(end -1.143 0.5588)
			(stroke
				(width 0.1)
				(type default)
			)
			(layer "F.SilkS")
		)
		(fp_line
			(start 1.143 0.5588)
			(end 1.143 -0.5588)
			(stroke
				(width 0.1)
				(type default)
			)
			(layer "F.SilkS")
		)
		(fp_line
			(start -1.143 0.5588)
			(end 1.143 0.5588)
			(stroke
				(width 0.1)
				(type default)
			)
			(layer "F.SilkS")
		)
		(fp_poly
			(pts
				(xy -1.143 0.5588) (xy 1.143 0.5588) (xy 1.143 -0.5588) (xy -1.143 -0.5588)
			)
			(stroke
				(width 0)
				(type default)
			)
			(fill no)
			(layer "F.CrtYd")
		)
		(fp_line
			(start 0.508 -0.3048)
			(end -0.508 -0.3048)
			(stroke
				(width 0.1)
				(type default)
			)
			(layer "F.Fab")
		)
		(fp_line
			(start -0.508 -0.3048)
			(end -0.508 0.3048)
			(stroke
				(width 0.1)
				(type default)
			)
			(layer "F.Fab")
		)
		(fp_line
			(start 0.508 0.3048)
			(end 0.508 -0.3048)
			(stroke
				(width 0.1)
				(type default)
			)
			(layer "F.Fab")
		)
		(fp_line
			(start -0.508 0.3048)
			(end 0.508 0.3048)
			(stroke
				(width 0.1)
				(type default)
			)
			(layer "F.Fab")
		)
		(pad "1" smd rect
			(at -0.5334 0 90)
			(size 0.7112 0.6096)
			(layers "F.Cu" "F.Mask" "F.Paste")
			(net "FPGA_FLASH_DQ2")
		)
		(pad "2" smd rect
			(at 0.5334 0 90)
			(size 0.7112 0.6096)
			(layers "F.Cu" "F.Mask" "F.Paste")
			(net "FLASH_DQ2")
		)
		(zone
			(layer "F.Cu")
			(hatch none 0.5)
			(connect_pads
				(clearance 0)
			)
			(min_thickness 0.25)
			(keepout
				(tracks allowed)
				(vias not_allowed)
				(pads allowed)
				(copperpour not_allowed)
				(footprints allowed)
			)
			(placement
				(enabled no)
				(sheetname "")
			)
			(fill
				(thermal_gap 0.5)
				(thermal_bridge_width 0.5)
				(island_removal_mode 0)
			)
			(polygon
				(pts
					(xy 98.6028 -87.4268) (xy 98.6028 -87.5792) (xy 97.9932 -87.5792) (xy 97.9932 -87.4268)
				)
			)
		)
		(zone
			(layer "F.Cu")
			(hatch none 0.5)
			(connect_pads
				(clearance 0)
			)
			(min_thickness 0.25)
			(keepout
				(tracks not_allowed)
				(vias allowed)
				(pads allowed)
				(copperpour not_allowed)
				(footprints allowed)
			)
			(placement
				(enabled no)
				(sheetname "")
			)
			(fill
				(thermal_gap 0.5)
				(thermal_bridge_width 0.5)
				(island_removal_mode 0)
			)
			(polygon
				(pts
					(xy 98.6028 -87.4268) (xy 98.6028 -87.5792) (xy 97.9932 -87.5792) (xy 97.9932 -87.4268)
				)
			)
		)
	)
)
